(kicad_pcb
	(version 20260206)
	(generator "pcbnew")
	(generator_version "10.0")
	(general
		(thickness 1.6)
		(legacy_teardrops no)
	)
	(paper "A4")
	(title_block
		(title "v1-pdb — T6M_PDB_D_0927_0900.brd")
		(comment 1 "Open CloudServer (Microsoft) / footprints 139-141 of 321")
	)
	(layers
		(0 "F.Cu" signal "TOP")
		(4 "In1.Cu" signal "GND")
		(6 "In2.Cu" signal "IN1")
		(8 "In3.Cu" signal "VCC")
		(10 "In4.Cu" signal "VCC1")
		(12 "In5.Cu" signal "IN2")
		(14 "In6.Cu" signal "GND1")
		(2 "B.Cu" signal "BOTTOM")
		(9 "F.Adhes" user "F.Adhesive")
		(11 "B.Adhes" user "B.Adhesive")
		(13 "F.Paste" user "Package Geometry/Pastemask Top")
		(15 "B.Paste" user "Package Geometry/Pastemask Bottom")
		(5 "F.SilkS" user "Ref Des/Silkscreen Top")
		(7 "B.SilkS" user "Ref Des/Silkscreen Bottom")
		(1 "F.Mask" user "Board Geometry/Soldermask Top")
		(3 "B.Mask" user "Board Geometry/Soldermask Bottom")
		(17 "Dwgs.User" user "User.Drawings")
		(19 "Cmts.User" user "User.Comments")
		(21 "Eco1.User" user "User.Eco1")
		(23 "Eco2.User" user "User.Eco2")
		(25 "Edge.Cuts" user "Board Geometry/Outline")
		(27 "Margin" user)
		(31 "F.CrtYd" user "Package Geometry/Place Bound Top")
		(29 "B.CrtYd" user "Package Geometry/Place Bound Bottom")
		(35 "F.Fab" user "Ref Des/Assembly Top")
		(33 "B.Fab" user "Ref Des/Assembly Bottom")
	)
	(footprint ""
		(layer "F.Cu")
		(at 4.50469 -52.571904)
		(property "Reference" "J21"
			(at -3.5179 -4.511548 0)
			(unlocked yes)
			(layer "F.SilkS")
			(effects
				(font
					(size 0.7874 0.5842)
					(thickness 0.1524)
				)
				(justify left)
			)
		)
		(property "Value" ""
			(at 0 0 0)
			(layer "F.Fab")
			(effects
				(font
					(size 1.27 1.27)
				)
			)
		)
		(duplicate_pad_numbers_are_jumpers no)
		(fp_line
			(start -3.370072 -3.81)
			(end 12.260072 -3.81)
			(stroke
				(width 0.1524)
				(type default)
			)
			(layer "F.SilkS")
		)
		(fp_line
			(start -3.370072 12.830048)
			(end -3.370072 -3.81)
			(stroke
				(width 0.1524)
				(type default)
			)
			(layer "F.SilkS")
		)
		(fp_line
			(start 12.260072 -3.81)
			(end 12.260072 12.830048)
			(stroke
				(width 0.1524)
				(type default)
			)
			(layer "F.SilkS")
		)
		(fp_line
			(start 12.260072 12.830048)
			(end -3.370072 12.830048)
			(stroke
				(width 0.1524)
				(type default)
			)
			(layer "F.SilkS")
		)
		(fp_poly
			(pts
				(xy -3.576828 0) (xy -5.0038 0.713486) (xy -5.0038 -0.713486)
			)
			(stroke
				(width 0)
				(type default)
			)
			(fill yes)
			(layer "F.SilkS")
		)
		(fp_poly
			(pts
				(xy -0.762 0.762) (xy 8.382 0.762) (xy 8.382 -1.8034) (xy 9.652 -1.8034) (xy 9.652 -3.302) (xy 0.508 -3.302)
				(xy 0.508 -0.762) (xy -0.762 -0.762)
			)
			(stroke
				(width 0)
				(type default)
			)
			(fill no)
			(layer "B.CrtYd")
		)
		(fp_poly
			(pts
				(arc
					(start 0.6604 6.35)
					(mid -3.2004 6.35)
					(end 0.6604 6.35)
				)
			)
			(stroke
				(width 0)
				(type default)
			)
			(fill no)
			(layer "B.CrtYd")
		)
		(fp_poly
			(pts
				(arc
					(start 12.0904 6.35)
					(mid 8.2296 6.35)
					(end 12.0904 6.35)
				)
			)
			(stroke
				(width 0)
				(type default)
			)
			(fill no)
			(layer "B.CrtYd")
		)
		(fp_poly
			(pts
				(xy -3.370072 12.830048) (xy 12.260072 12.830048) (xy 12.260072 -3.81) (xy -3.370072 -3.81)
			)
			(stroke
				(width 0)
				(type default)
			)
			(fill no)
			(layer "F.CrtYd")
		)
		(fp_line
			(start -3.370072 -3.81)
			(end 12.260072 -3.81)
			(stroke
				(width 0.1)
				(type default)
			)
			(layer "F.Fab")
		)
		(fp_line
			(start -3.370072 12.830048)
			(end -3.370072 -3.81)
			(stroke
				(width 0.1)
				(type default)
			)
			(layer "F.Fab")
		)
		(fp_line
			(start 12.260072 -3.81)
			(end 12.260072 12.830048)
			(stroke
				(width 0.1)
				(type default)
			)
			(layer "F.Fab")
		)
		(fp_line
			(start 12.260072 12.830048)
			(end -3.370072 12.830048)
			(stroke
				(width 0.1)
				(type default)
			)
			(layer "F.Fab")
		)
		(fp_poly
			(pts
				(xy -3.576828 0) (xy -5.0038 0.713486) (xy -5.0038 -0.713486)
			)
			(stroke
				(width 0)
				(type default)
			)
			(fill yes)
			(layer "F.Fab")
		)
		(fp_text user "2"
			(at -3.9624 -2.428748 0)
			(unlocked yes)
			(layer "F.SilkS")
			(effects
				(font
					(size 0.7874 0.5842)
					(thickness 0.1524)
				)
			)
		)
		(fp_text user "1"
			(at -3.9116 -0.930148 0)
			(unlocked yes)
			(layer "F.SilkS")
			(effects
				(font
					(size 0.7874 0.5842)
					(thickness 0.1524)
				)
			)
		)
		(fp_text user "8"
			(at 12.7762 -2.555748 0)
			(unlocked yes)
			(layer "F.SilkS")
			(effects
				(font
					(size 0.7874 0.5842)
					(thickness 0.1524)
				)
			)
		)
		(fp_text user "7"
			(at 12.7762 -0.091948 0)
			(unlocked yes)
			(layer "F.SilkS")
			(effects
				(font
					(size 0.7874 0.5842)
					(thickness 0.1524)
				)
			)
		)
		(fp_text user "1"
			(at -1.2954 0.085852 0)
			(unlocked yes)
			(layer "B.SilkS")
			(effects
				(font
					(size 0.7874 0.5842)
					(thickness 0.1524)
				)
				(justify mirror)
			)
		)
		(fp_text user "2"
			(at 0 -2.581148 0)
			(unlocked yes)
			(layer "B.SilkS")
			(effects
				(font
					(size 0.7874 0.5842)
					(thickness 0.1524)
				)
				(justify mirror)
			)
		)
		(fp_text user "7"
			(at 8.8138 0.238252 0)
			(unlocked yes)
			(layer "B.SilkS")
			(effects
				(font
					(size 0.7874 0.5842)
					(thickness 0.1524)
				)
				(justify mirror)
			)
		)
		(fp_text user "8"
			(at 10.0838 -2.403348 0)
			(unlocked yes)
			(layer "B.SilkS")
			(effects
				(font
					(size 0.7874 0.5842)
					(thickness 0.1524)
				)
				(justify mirror)
			)
		)
		(fp_text user "1"
			(at -1.2954 0.085852 0)
			(unlocked yes)
			(layer "B.Fab")
			(effects
				(font
					(size 0.7874 0.5842)
					(thickness 0.000001)
				)
				(justify mirror)
			)
		)
		(fp_text user "2"
			(at 0 -2.581148 0)
			(unlocked yes)
			(layer "B.Fab")
			(effects
				(font
					(size 0.7874 0.5842)
					(thickness 0.000001)
				)
				(justify mirror)
			)
		)
		(fp_text user "7"
			(at 8.8138 0.238252 0)
			(unlocked yes)
			(layer "B.Fab")
			(effects
				(font
					(size 0.7874 0.5842)
					(thickness 0.000001)
				)
				(justify mirror)
			)
		)
		(fp_text user "8"
			(at 10.0838 -2.403348 0)
			(unlocked yes)
			(layer "B.Fab")
			(effects
				(font
					(size 0.7874 0.5842)
					(thickness 0.000001)
				)
				(justify mirror)
			)
		)
		(fp_text user "2"
			(at -3.9624 -2.428748 0)
			(unlocked yes)
			(layer "F.Fab")
			(effects
				(font
					(size 0.7874 0.5842)
					(thickness 0.000001)
				)
			)
		)
		(fp_text user "1"
			(at -3.9116 -0.930148 0)
			(unlocked yes)
			(layer "F.Fab")
			(effects
				(font
					(size 0.7874 0.5842)
					(thickness 0.000001)
				)
			)
		)
		(fp_text user "8"
			(at 12.7762 -2.555748 0)
			(unlocked yes)
			(layer "F.Fab")
			(effects
				(font
					(size 0.7874 0.5842)
					(thickness 0.000001)
				)
			)
		)
		(fp_text user "7"
			(at 12.7762 -0.091948 0)
			(unlocked yes)
			(layer "F.Fab")
			(effects
				(font
					(size 0.7874 0.5842)
					(thickness 0.000001)
				)
			)
		)
		(pad "" np_thru_hole circle
			(at -1.27 6.35)
			(size 3.3528 3.3528)
			(drill 3.3528)
			(layers "*.Cu" "*.Mask")
			(clearance 0.381)
			(thermal_gap 0.381)
		)
		(pad "" np_thru_hole circle
			(at 10.16 6.35)
			(size 3.3528 3.3528)
			(drill 3.3528)
			(layers "*.Cu" "*.Mask")
			(clearance 0.381)
			(thermal_gap 0.381)
		)
		(pad "1" thru_hole rect
			(at 0 0)
			(size 1.397 1.397)
			(drill 0.9906)
			(layers "*.Cu" "*.Mask")
			(remove_unused_layers no)
			(net "UART_RTS_P2_L_N")
			(clearance 0.0508)
			(thermal_gap 0.0508)
			(padstack
				(mode front_inner_back)
				(layer "Inner"
					(shape circle)
					(size 1.397 1.397)
					(clearance 0.0508)
				)
				(layer "B.Cu"
					(shape rect)
					(size 1.397 1.397)
					(clearance 0.0508)
				)
			)
		)
		(pad "2" thru_hole circle
			(at 1.27 -2.54)
			(size 1.397 1.397)
			(drill 0.9906)
			(layers "*.Cu" "*.Mask")
			(remove_unused_layers no)
			(net "UART_DSR_P2_L_N")
			(clearance 0.0508)
			(thermal_gap 0.0508)
		)
		(pad "3" thru_hole circle
			(at 2.54 0)
			(size 1.397 1.397)
			(drill 0.9906)
			(layers "*.Cu" "*.Mask")
			(remove_unused_layers no)
			(net "UART_RX_P2_L")
			(clearance 0.0508)
			(thermal_gap 0.0508)
		)
		(pad "4" thru_hole circle
			(at 3.81 -2.54)
			(size 1.397 1.397)
			(drill 0.9906)
			(layers "*.Cu" "*.Mask")
			(remove_unused_layers no)
			(net "GND")
			(clearance 0.0508)
			(thermal_gap 0.0508)
		)
		(pad "5" thru_hole circle
			(at 5.08 0)
			(size 1.397 1.397)
			(drill 0.9906)
			(layers "*.Cu" "*.Mask")
			(remove_unused_layers no)
			(net "GND")
			(clearance 0.0508)
			(thermal_gap 0.0508)
		)
		(pad "6" thru_hole circle
			(at 6.35 -2.54)
			(size 1.397 1.397)
			(drill 0.9906)
			(layers "*.Cu" "*.Mask")
			(remove_unused_layers no)
			(net "UART_TX_P2_L")
			(clearance 0.0508)
			(thermal_gap 0.0508)
		)
		(pad "7" thru_hole circle
			(at 7.62 0)
			(size 1.397 1.397)
			(drill 0.9906)
			(layers "*.Cu" "*.Mask")
			(remove_unused_layers no)
			(net "UART_DTR_P2_L_N")
			(clearance 0.0508)
			(thermal_gap 0.0508)
		)
		(pad "8" thru_hole circle
			(at 8.89 -2.54)
			(size 1.397 1.397)
			(drill 0.9906)
			(layers "*.Cu" "*.Mask")
			(remove_unused_layers no)
			(net "UART_CTS_P2_L_N")
			(clearance 0.0508)
			(thermal_gap 0.0508)
		)
		(zone
			(layers "F.Cu" "B.Cu" "In1.Cu" "In2.Cu" "In3.Cu" "In4.Cu" "In5.Cu" "In6.Cu")
			(hatch none 0.5)
			(connect_pads
				(clearance 0)
			)
			(min_thickness 0.25)
			(keepout
				(tracks not_allowed)
				(vias allowed)
				(pads allowed)
				(copperpour not_allowed)
				(footprints allowed)
			)
			(placement
				(enabled no)
				(sheetname "")
			)
			(fill
				(thermal_gap 0.5)
				(thermal_bridge_width 0.5)
				(island_removal_mode 0)
			)
			(polygon
				(pts
					(arc
						(start 5.31749 -46.221904)
						(mid 1.15189 -46.221904)
						(end 5.31749 -46.221904)
					)
				)
			)
		)
		(zone
			(layers "F.Cu" "B.Cu" "In1.Cu" "In2.Cu" "In3.Cu" "In4.Cu" "In5.Cu" "In6.Cu")
			(hatch none 0.5)
			(connect_pads
				(clearance 0)
			)
			(min_thickness 0.25)
			(keepout
				(tracks not_allowed)
				(vias allowed)
				(pads allowed)
				(copperpour not_allowed)
				(footprints allowed)
			)
			(placement
				(enabled no)
				(sheetname "")
			)
			(fill
				(thermal_gap 0.5)
				(thermal_bridge_width 0.5)
				(island_removal_mode 0)
			)
			(polygon
				(pts
					(arc
						(start 16.74749 -46.221904)
						(mid 12.58189 -46.221904)
						(end 16.74749 -46.221904)
					)
				)
			)
		)
	)
	(footprint ""
		(layer "F.Cu")
		(at 25.857708 -365.50092)
		(property "Reference" "R79"
			(at -3.917442 -0.225298 0)
			(unlocked yes)
			(layer "F.SilkS")
			(effects
				(font
					(size 0.7874 0.5842)
					(thickness 0.1524)
				)
				(justify left)
			)
		)
		(property "Value" ""
			(at 0 0 0)
			(layer "F.Fab")
			(effects
				(font
					(size 1.27 1.27)
				)
			)
		)
		(duplicate_pad_numbers_are_jumpers no)
		(fp_line
			(start -0.7874 -0.4064)
			(end 0.7874 -0.4064)
			(stroke
				(width 0.1524)
				(type default)
			)
			(layer "F.SilkS")
		)
		(fp_line
			(start -0.7874 0.4064)
			(end -0.7874 -0.4064)
			(stroke
				(width 0.1524)
				(type default)
			)
			(layer "F.SilkS")
		)
		(fp_line
			(start 0.7874 -0.4064)
			(end 0.7874 0.4064)
			(stroke
				(width 0.1524)
				(type default)
			)
			(layer "F.SilkS")
		)
		(fp_line
			(start 0.7874 0.4064)
			(end -0.7874 0.4064)
			(stroke
				(width 0.1524)
				(type default)
			)
			(layer "F.SilkS")
		)
		(fp_poly
			(pts
				(xy -0.508 0.2794) (xy -0.508 0.2286) (xy -0.635 0.2286) (xy -0.635 -0.254) (xy -0.5334 -0.254)
				(xy -0.5334 -0.2794) (xy 0.5334 -0.2794) (xy 0.5334 -0.254) (xy 0.635 -0.254) (xy 0.635 0.254) (xy 0.5334 0.254)
				(xy 0.5334 0.2794)
			)
			(stroke
				(width 0)
				(type default)
			)
			(fill no)
			(layer "F.CrtYd")
		)
		(pad "1" smd rect
			(at 0.40005 0)
			(size 0.4572 0.508)
			(layers "F.Cu" "F.Mask" "F.Paste")
			(net "PSU5_PS_KILL")
		)
		(pad "2" smd rect
			(at -0.40005 0)
			(size 0.4572 0.508)
			(layers "F.Cu" "F.Mask" "F.Paste")
			(net "GND")
		)
	)
	(footprint ""
		(layer "F.Cu")
		(at 74.775568 -397.262604 90)
		(property "Reference" "C68"
			(at -1.662176 -4.812538 90)
			(unlocked yes)
			(layer "F.SilkS")
			(effects
				(font
					(size 0.7874 0.5842)
					(thickness 0.1524)
				)
				(justify left)
			)
		)
		(property "Value" ""
			(at 0 0 90)
			(layer "F.Fab")
			(effects
				(font
					(size 1.27 1.27)
				)
			)
		)
		(duplicate_pad_numbers_are_jumpers no)
		(fp_line
			(start 0.7874 -0.4064)
			(end 0.7874 0.4064)
			(stroke
				(width 0.1524)
				(type default)
			)
			(layer "F.SilkS")
		)
		(fp_line
			(start -0.7874 -0.4064)
			(end 0.7874 -0.4064)
			(stroke
				(width 0.1524)
				(type default)
			)
			(layer "F.SilkS")
		)
		(fp_line
			(start 0 0.381)
			(end 0 -0.381)
			(stroke
				(width 0.1524)
				(type default)
			)
			(layer "F.SilkS")
		)
		(fp_line
			(start 0.7874 0.4064)
			(end -0.7874 0.4064)
			(stroke
				(width 0.1524)
				(type default)
			)
			(layer "F.SilkS")
		)
		(fp_line
			(start -0.7874 0.4064)
			(end -0.7874 -0.4064)
			(stroke
				(width 0.1524)
				(type default)
			)
			(layer "F.SilkS")
		)
		(fp_poly
			(pts
				(xy -0.5334 0.254) (xy -0.635 0.254) (xy -0.635 0.2286) (xy -0.635 -0.254) (xy -0.5334 -0.254) (xy -0.5334 -0.2794)
				(xy 0.5334 -0.2794) (xy 0.5334 -0.254) (xy 0.635 -0.254) (xy 0.635 0.254) (xy 0.5334 0.254) (xy 0.5334 0.2794)
				(xy -0.508 0.2794) (xy -0.5334 0.2794)
			)
			(stroke
				(width 0)
				(type default)
			)
			(fill no)
			(layer "F.CrtYd")
		)
		(pad "1" smd rect
			(at 0.40005 0 90)
			(size 0.4572 0.508)
			(layers "F.Cu" "F.Mask" "F.Paste")
			(net "P12V")
		)
		(pad "2" smd rect
			(at -0.40005 0 90)
			(size 0.4572 0.508)
			(layers "F.Cu" "F.Mask" "F.Paste")
			(net "GND")
		)
	)
)
